(kicad_pcb
	(version 20260206)
	(generator "pcbnew")
	(generator_version "10.0")
	(general
		(thickness 1.6)
		(legacy_teardrops no)
	)
	(paper "A4")
	(title_block
		(title "01162023_DA0F0TEBIF0_F0T_Expander_BD_F_brd_V02_OCP.brd")
		(comment 1 "Grand Teton / footprints 5810-5816 of 9728")
	)
	(layers
		(0 "F.Cu" signal "TOP")
		(4 "In1.Cu" signal "GND")
		(6 "In2.Cu" signal "VCC")
		(8 "In3.Cu" signal "VCC1")
		(10 "In4.Cu" signal "GND1")
		(12 "In5.Cu" signal "IN1")
		(14 "In6.Cu" signal "GND2")
		(16 "In7.Cu" signal "IN2")
		(18 "In8.Cu" signal "GND3")
		(20 "In9.Cu" signal "IN3")
		(22 "In10.Cu" signal "GND4")
		(24 "In11.Cu" signal "IN4")
		(26 "In12.Cu" signal "GND5")
		(28 "In13.Cu" signal "IN5")
		(30 "In14.Cu" signal "GND6")
		(32 "In15.Cu" signal "IN6")
		(34 "In16.Cu" signal "GND7")
		(2 "B.Cu" signal "BOTTOM")
		(9 "F.Adhes" user "F.Adhesive")
		(11 "B.Adhes" user "B.Adhesive")
		(13 "F.Paste" user "Package Geometry/Pastemask Top")
		(15 "B.Paste" user "Package Geometry/Pastemask Bottom")
		(5 "F.SilkS" user "Ref Des/Silkscreen Top")
		(7 "B.SilkS" user "Ref Des/Silkscreen Bottom")
		(1 "F.Mask" user "Board Geometry/Soldermask Top")
		(3 "B.Mask" user "Board Geometry/Soldermask Bottom")
		(17 "Dwgs.User" user "User.Drawings")
		(19 "Cmts.User" user "User.Comments")
		(21 "Eco1.User" user "User.Eco1")
		(23 "Eco2.User" user "User.Eco2")
		(25 "Edge.Cuts" user "Board Geometry/Outline")
		(27 "Margin" user)
		(31 "F.CrtYd" user "Package Geometry/Place Bound Top")
		(29 "B.CrtYd" user "Package Geometry/Place Bound Bottom")
		(35 "F.Fab" user "Ref Des/Assembly Top")
		(33 "B.Fab" user "Ref Des/Assembly Bottom")
	)
	(footprint ""
		(layer "F.Cu")
		(at 336.515456 -279.101804)
		(property "Reference" "PC138"
			(at 0 0 0)
			(layer "F.SilkS")
			(hide yes)
			(effects
				(font
					(size 1.27 1.27)
				)
			)
		)
		(property "Value" ""
			(at 0 0 0)
			(layer "F.Fab")
			(effects
				(font
					(size 1.27 1.27)
				)
			)
		)
		(duplicate_pad_numbers_are_jumpers no)
		(fp_line
			(start -0.7874 -0.4064)
			(end 0.7874 -0.4064)
			(stroke
				(width 0.1524)
				(type default)
			)
			(layer "F.SilkS")
		)
		(fp_line
			(start -0.7874 0.4064)
			(end -0.7874 -0.4064)
			(stroke
				(width 0.1524)
				(type default)
			)
			(layer "F.SilkS")
		)
		(fp_line
			(start 0.7874 -0.4064)
			(end 0.7874 0.4064)
			(stroke
				(width 0.1524)
				(type default)
			)
			(layer "F.SilkS")
		)
		(fp_line
			(start 0.7874 0.4064)
			(end -0.7874 0.4064)
			(stroke
				(width 0.1524)
				(type default)
			)
			(layer "F.SilkS")
		)
		(fp_line
			(start -0.67945 -0.305054)
			(end -0.12065 -0.305054)
			(stroke
				(width 0.1)
				(type default)
			)
			(layer "F.Fab")
		)
		(fp_line
			(start -0.67945 0.3048)
			(end -0.67945 -0.305054)
			(stroke
				(width 0.1)
				(type default)
			)
			(layer "F.Fab")
		)
		(fp_line
			(start -0.12065 -0.305054)
			(end -0.12065 -0.2794)
			(stroke
				(width 0.1)
				(type default)
			)
			(layer "F.Fab")
		)
		(fp_line
			(start -0.12065 -0.2794)
			(end 0.12065 -0.2794)
			(stroke
				(width 0.1)
				(type default)
			)
			(layer "F.Fab")
		)
		(fp_line
			(start -0.12065 0.2794)
			(end -0.12065 0.3048)
			(stroke
				(width 0.1)
				(type default)
			)
			(layer "F.Fab")
		)
		(fp_line
			(start -0.12065 0.3048)
			(end -0.67945 0.3048)
			(stroke
				(width 0.1)
				(type default)
			)
			(layer "F.Fab")
		)
		(fp_line
			(start 0.120396 0.2794)
			(end -0.12065 0.2794)
			(stroke
				(width 0.1)
				(type default)
			)
			(layer "F.Fab")
		)
		(fp_line
			(start 0.120396 0.3048)
			(end 0.120396 0.2794)
			(stroke
				(width 0.1)
				(type default)
			)
			(layer "F.Fab")
		)
		(fp_line
			(start 0.12065 -0.3048)
			(end 0.67945 -0.3048)
			(stroke
				(width 0.1)
				(type default)
			)
			(layer "F.Fab")
		)
		(fp_line
			(start 0.12065 -0.2794)
			(end 0.12065 -0.3048)
			(stroke
				(width 0.1)
				(type default)
			)
			(layer "F.Fab")
		)
		(fp_line
			(start 0.67945 -0.3048)
			(end 0.67945 0.3048)
			(stroke
				(width 0.1)
				(type default)
			)
			(layer "F.Fab")
		)
		(fp_line
			(start 0.67945 0.3048)
			(end 0.120396 0.3048)
			(stroke
				(width 0.1)
				(type default)
			)
			(layer "F.Fab")
		)
		(pad "1" smd circle
			(at -0.40005 0)
			(size 0 0)
			(layers "F.Cu" "F.Mask" "F.Paste")
			(net "SW_P12V_P0V8_PEX2_FLT")
		)
		(pad "2" smd circle
			(at 0.40005 0)
			(size 0 0)
			(layers "F.Cu" "F.Mask" "F.Paste")
			(net "GND")
		)
	)
	(footprint ""
		(layer "F.Cu")
		(at 446.787524 -25.342342 -90)
		(property "Reference" "R455"
			(at 0 0 270)
			(layer "F.SilkS")
			(hide yes)
			(effects
				(font
					(size 1.27 1.27)
				)
			)
		)
		(property "Value" ""
			(at 0 0 270)
			(layer "F.Fab")
			(effects
				(font
					(size 1.27 1.27)
				)
			)
		)
		(duplicate_pad_numbers_are_jumpers no)
		(fp_line
			(start -0.7874 0.4064)
			(end -0.7874 -0.4064)
			(stroke
				(width 0.1524)
				(type default)
			)
			(layer "F.SilkS")
		)
		(fp_line
			(start 0.7874 0.4064)
			(end -0.7874 0.4064)
			(stroke
				(width 0.1524)
				(type default)
			)
			(layer "F.SilkS")
		)
		(fp_line
			(start -0.7874 -0.4064)
			(end 0.7874 -0.4064)
			(stroke
				(width 0.1524)
				(type default)
			)
			(layer "F.SilkS")
		)
		(fp_line
			(start 0.7874 -0.4064)
			(end 0.7874 0.4064)
			(stroke
				(width 0.1524)
				(type default)
			)
			(layer "F.SilkS")
		)
		(fp_line
			(start -0.67945 0.3048)
			(end -0.67945 -0.305054)
			(stroke
				(width 0.1)
				(type default)
			)
			(layer "F.Fab")
		)
		(fp_line
			(start -0.12065 0.3048)
			(end -0.67945 0.3048)
			(stroke
				(width 0.1)
				(type default)
			)
			(layer "F.Fab")
		)
		(fp_line
			(start 0.120396 0.3048)
			(end 0.120396 0.2794)
			(stroke
				(width 0.1)
				(type default)
			)
			(layer "F.Fab")
		)
		(fp_line
			(start 0.67945 0.3048)
			(end 0.120396 0.3048)
			(stroke
				(width 0.1)
				(type default)
			)
			(layer "F.Fab")
		)
		(fp_line
			(start -0.12065 0.2794)
			(end -0.12065 0.3048)
			(stroke
				(width 0.1)
				(type default)
			)
			(layer "F.Fab")
		)
		(fp_line
			(start 0.120396 0.2794)
			(end -0.12065 0.2794)
			(stroke
				(width 0.1)
				(type default)
			)
			(layer "F.Fab")
		)
		(fp_line
			(start -0.12065 -0.2794)
			(end 0.12065 -0.2794)
			(stroke
				(width 0.1)
				(type default)
			)
			(layer "F.Fab")
		)
		(fp_line
			(start 0.12065 -0.2794)
			(end 0.12065 -0.3048)
			(stroke
				(width 0.1)
				(type default)
			)
			(layer "F.Fab")
		)
		(fp_line
			(start 0.12065 -0.3048)
			(end 0.67945 -0.3048)
			(stroke
				(width 0.1)
				(type default)
			)
			(layer "F.Fab")
		)
		(fp_line
			(start 0.67945 -0.3048)
			(end 0.67945 0.3048)
			(stroke
				(width 0.1)
				(type default)
			)
			(layer "F.Fab")
		)
		(fp_line
			(start -0.67945 -0.305054)
			(end -0.12065 -0.305054)
			(stroke
				(width 0.1)
				(type default)
			)
			(layer "F.Fab")
		)
		(fp_line
			(start -0.12065 -0.305054)
			(end -0.12065 -0.2794)
			(stroke
				(width 0.1)
				(type default)
			)
			(layer "F.Fab")
		)
		(pad "1" smd circle
			(at -0.40005 0 270)
			(size 0 0)
			(layers "F.Cu" "F.Mask" "F.Paste")
			(net "GND")
		)
		(pad "2" smd circle
			(at 0.40005 0 270)
			(size 0 0)
			(layers "F.Cu" "F.Mask" "F.Paste")
			(net "DUALPORT_N_SSD15")
		)
	)
	(footprint ""
		(layer "F.Cu")
		(at 421.705532 -356.244906 90)
		(property "Reference" "C812"
			(at 0 0 90)
			(layer "F.SilkS")
			(hide yes)
			(effects
				(font
					(size 1.27 1.27)
				)
			)
		)
		(property "Value" ""
			(at 0 0 90)
			(layer "F.Fab")
			(effects
				(font
					(size 1.27 1.27)
				)
			)
		)
		(duplicate_pad_numbers_are_jumpers no)
		(fp_line
			(start 0.299974 -0.150114)
			(end 0.299974 0.150114)
			(stroke
				(width 0.1)
				(type default)
			)
			(layer "F.Fab")
		)
		(fp_line
			(start -0.299974 -0.150114)
			(end 0.299974 -0.150114)
			(stroke
				(width 0.1)
				(type default)
			)
			(layer "F.Fab")
		)
		(fp_line
			(start 0.299974 0.150114)
			(end -0.299974 0.150114)
			(stroke
				(width 0.1)
				(type default)
			)
			(layer "F.Fab")
		)
		(fp_line
			(start -0.299974 0.150114)
			(end -0.299974 -0.150114)
			(stroke
				(width 0.1)
				(type default)
			)
			(layer "F.Fab")
		)
		(pad "1" smd rect
			(at -0.2667 0 90)
			(size 0.3048 0.381)
			(layers "F.Cu" "F.Mask" "F.Paste")
			(net "P5E_PEX3_STN7_TX_DP<118>")
		)
		(pad "2" smd rect
			(at 0.2667 0 90)
			(size 0.3048 0.381)
			(layers "F.Cu" "F.Mask" "F.Paste")
			(net "P5E_PEX3_STN7_TX_C_DP<118>")
		)
	)
	(footprint ""
		(layer "F.Cu")
		(at 154.699716 -154.327352 180)
		(property "Reference" "R128"
			(at 0 0 180)
			(layer "F.SilkS")
			(hide yes)
			(effects
				(font
					(size 1.27 1.27)
				)
			)
		)
		(property "Value" ""
			(at 0 0 180)
			(layer "F.Fab")
			(effects
				(font
					(size 1.27 1.27)
				)
			)
		)
		(duplicate_pad_numbers_are_jumpers no)
		(fp_line
			(start 0.7874 0.4064)
			(end -0.7874 0.4064)
			(stroke
				(width 0.1524)
				(type default)
			)
			(layer "F.SilkS")
		)
		(fp_line
			(start 0.7874 -0.4064)
			(end 0.7874 0.4064)
			(stroke
				(width 0.1524)
				(type default)
			)
			(layer "F.SilkS")
		)
		(fp_line
			(start -0.7874 0.4064)
			(end -0.7874 -0.4064)
			(stroke
				(width 0.1524)
				(type default)
			)
			(layer "F.SilkS")
		)
		(fp_line
			(start -0.7874 -0.4064)
			(end 0.7874 -0.4064)
			(stroke
				(width 0.1524)
				(type default)
			)
			(layer "F.SilkS")
		)
		(fp_line
			(start 0.67945 0.3048)
			(end 0.120396 0.3048)
			(stroke
				(width 0.1)
				(type default)
			)
			(layer "F.Fab")
		)
		(fp_line
			(start 0.67945 -0.3048)
			(end 0.67945 0.3048)
			(stroke
				(width 0.1)
				(type default)
			)
			(layer "F.Fab")
		)
		(fp_line
			(start 0.12065 -0.2794)
			(end 0.12065 -0.3048)
			(stroke
				(width 0.1)
				(type default)
			)
			(layer "F.Fab")
		)
		(fp_line
			(start 0.12065 -0.3048)
			(end 0.67945 -0.3048)
			(stroke
				(width 0.1)
				(type default)
			)
			(layer "F.Fab")
		)
		(fp_line
			(start 0.120396 0.3048)
			(end 0.120396 0.2794)
			(stroke
				(width 0.1)
				(type default)
			)
			(layer "F.Fab")
		)
		(fp_line
			(start 0.120396 0.2794)
			(end -0.12065 0.2794)
			(stroke
				(width 0.1)
				(type default)
			)
			(layer "F.Fab")
		)
		(fp_line
			(start -0.12065 0.3048)
			(end -0.67945 0.3048)
			(stroke
				(width 0.1)
				(type default)
			)
			(layer "F.Fab")
		)
		(fp_line
			(start -0.12065 0.2794)
			(end -0.12065 0.3048)
			(stroke
				(width 0.1)
				(type default)
			)
			(layer "F.Fab")
		)
		(fp_line
			(start -0.12065 -0.2794)
			(end 0.12065 -0.2794)
			(stroke
				(width 0.1)
				(type default)
			)
			(layer "F.Fab")
		)
		(fp_line
			(start -0.12065 -0.305054)
			(end -0.12065 -0.2794)
			(stroke
				(width 0.1)
				(type default)
			)
			(layer "F.Fab")
		)
		(fp_line
			(start -0.67945 0.3048)
			(end -0.67945 -0.305054)
			(stroke
				(width 0.1)
				(type default)
			)
			(layer "F.Fab")
		)
		(fp_line
			(start -0.67945 -0.305054)
			(end -0.12065 -0.305054)
			(stroke
				(width 0.1)
				(type default)
			)
			(layer "F.Fab")
		)
		(pad "1" smd circle
			(at -0.40005 0 180)
			(size 0 0)
			(layers "F.Cu" "F.Mask" "F.Paste")
			(net "NIC2_SLOT_ID0")
		)
		(pad "2" smd circle
			(at 0.40005 0 180)
			(size 0 0)
			(layers "F.Cu" "F.Mask" "F.Paste")
			(net "GND")
		)
	)
	(footprint ""
		(layer "F.Cu")
		(at 381.340106 -256.634234 180)
		(property "Reference" "C3572"
			(at 0 0 180)
			(layer "F.SilkS")
			(hide yes)
			(effects
				(font
					(size 1.27 1.27)
				)
			)
		)
		(property "Value" ""
			(at 0 0 180)
			(layer "F.Fab")
			(effects
				(font
					(size 1.27 1.27)
				)
			)
		)
		(duplicate_pad_numbers_are_jumpers no)
		(fp_line
			(start 1.2954 0.5842)
			(end -1.2954 0.5842)
			(stroke
				(width 0.1524)
				(type default)
			)
			(layer "F.SilkS")
		)
		(fp_line
			(start 1.2954 -0.5842)
			(end 1.2954 0.5842)
			(stroke
				(width 0.1524)
				(type default)
			)
			(layer "F.SilkS")
		)
		(fp_line
			(start -1.2954 0.5842)
			(end -1.2954 -0.5842)
			(stroke
				(width 0.1524)
				(type default)
			)
			(layer "F.SilkS")
		)
		(fp_line
			(start -1.2954 -0.5842)
			(end 1.2954 -0.5842)
			(stroke
				(width 0.1524)
				(type default)
			)
			(layer "F.SilkS")
		)
		(fp_line
			(start 1.1938 0.4064)
			(end 0.8636 0.4064)
			(stroke
				(width 0.1)
				(type default)
			)
			(layer "F.Fab")
		)
		(fp_line
			(start 1.1938 -0.4064)
			(end 1.1938 0.4064)
			(stroke
				(width 0.1)
				(type default)
			)
			(layer "F.Fab")
		)
		(fp_line
			(start 0.8636 0.4572)
			(end -0.8636 0.4572)
			(stroke
				(width 0.1)
				(type default)
			)
			(layer "F.Fab")
		)
		(fp_line
			(start 0.8636 0.4064)
			(end 0.8636 0.4572)
			(stroke
				(width 0.1)
				(type default)
			)
			(layer "F.Fab")
		)
		(fp_line
			(start 0.8636 -0.4064)
			(end 1.1938 -0.4064)
			(stroke
				(width 0.1)
				(type default)
			)
			(layer "F.Fab")
		)
		(fp_line
			(start 0.8636 -0.4572)
			(end 0.8636 -0.4064)
			(stroke
				(width 0.1)
				(type default)
			)
			(layer "F.Fab")
		)
		(fp_line
			(start -0.8636 0.4572)
			(end -0.8636 0.4064)
			(stroke
				(width 0.1)
				(type default)
			)
			(layer "F.Fab")
		)
		(fp_line
			(start -0.8636 0.4064)
			(end -1.1938 0.4064)
			(stroke
				(width 0.1)
				(type default)
			)
			(layer "F.Fab")
		)
		(fp_line
			(start -0.8636 -0.4064)
			(end -0.8636 -0.4572)
			(stroke
				(width 0.1)
				(type default)
			)
			(layer "F.Fab")
		)
		(fp_line
			(start -0.8636 -0.4572)
			(end 0.8636 -0.4572)
			(stroke
				(width 0.1)
				(type default)
			)
			(layer "F.Fab")
		)
		(fp_line
			(start -1.1938 0.4064)
			(end -1.1938 -0.4064)
			(stroke
				(width 0.1)
				(type default)
			)
			(layer "F.Fab")
		)
		(fp_line
			(start -1.1938 -0.4064)
			(end -0.8636 -0.4064)
			(stroke
				(width 0.1)
				(type default)
			)
			(layer "F.Fab")
		)
		(pad "1" smd rect
			(at -0.7366 0 90)
			(size 0.7112 0.8128)
			(layers "F.Cu" "F.Mask" "F.Paste")
			(net "PCEPLL5_VDDA18_PEX3_R")
		)
		(pad "2" smd rect
			(at 0.7366 0 90)
			(size 0.7112 0.8128)
			(layers "F.Cu" "F.Mask" "F.Paste")
			(net "GND")
		)
	)
	(footprint ""
		(layer "F.Cu")
		(at 41.069768 -350.098614 90)
		(property "Reference" "C2172"
			(at 0 0 90)
			(layer "F.SilkS")
			(hide yes)
			(effects
				(font
					(size 1.27 1.27)
				)
			)
		)
		(property "Value" ""
			(at 0 0 90)
			(layer "F.Fab")
			(effects
				(font
					(size 1.27 1.27)
				)
			)
		)
		(duplicate_pad_numbers_are_jumpers no)
		(fp_line
			(start 0.299974 -0.150114)
			(end 0.299974 0.150114)
			(stroke
				(width 0.1)
				(type default)
			)
			(layer "F.Fab")
		)
		(fp_line
			(start -0.299974 -0.150114)
			(end 0.299974 -0.150114)
			(stroke
				(width 0.1)
				(type default)
			)
			(layer "F.Fab")
		)
		(fp_line
			(start 0.299974 0.150114)
			(end -0.299974 0.150114)
			(stroke
				(width 0.1)
				(type default)
			)
			(layer "F.Fab")
		)
		(fp_line
			(start -0.299974 0.150114)
			(end -0.299974 -0.150114)
			(stroke
				(width 0.1)
				(type default)
			)
			(layer "F.Fab")
		)
		(pad "1" smd rect
			(at -0.2667 0 90)
			(size 0.3048 0.381)
			(layers "F.Cu" "F.Mask" "F.Paste")
			(net "P5E_PEX0_STN4_TX_DP<69>")
		)
		(pad "2" smd rect
			(at 0.2667 0 90)
			(size 0.3048 0.381)
			(layers "F.Cu" "F.Mask" "F.Paste")
			(net "P5E_PEX0_STN4_TX_C_DP<69>")
		)
	)
	(footprint ""
		(layer "F.Cu")
		(at 30.526736 -53.697124 -90)
		(property "Reference" "PC520"
			(at 0 0 270)
			(layer "F.SilkS")
			(hide yes)
			(effects
				(font
					(size 1.27 1.27)
				)
			)
		)
		(property "Value" ""
			(at 0 0 270)
			(layer "F.Fab")
			(effects
				(font
					(size 1.27 1.27)
				)
			)
		)
		(duplicate_pad_numbers_are_jumpers no)
		(fp_line
			(start -0.7874 0.4064)
			(end -0.7874 -0.4064)
			(stroke
				(width 0.1524)
				(type default)
			)
			(layer "F.SilkS")
		)
		(fp_line
			(start 0.7874 0.4064)
			(end -0.7874 0.4064)
			(stroke
				(width 0.1524)
				(type default)
			)
			(layer "F.SilkS")
		)
		(fp_line
			(start -0.7874 -0.4064)
			(end 0.7874 -0.4064)
			(stroke
				(width 0.1524)
				(type default)
			)
			(layer "F.SilkS")
		)
		(fp_line
			(start 0.7874 -0.4064)
			(end 0.7874 0.4064)
			(stroke
				(width 0.1524)
				(type default)
			)
			(layer "F.SilkS")
		)
		(fp_line
			(start -0.67945 0.3048)
			(end -0.67945 -0.305054)
			(stroke
				(width 0.1)
				(type default)
			)
			(layer "F.Fab")
		)
		(fp_line
			(start -0.12065 0.3048)
			(end -0.67945 0.3048)
			(stroke
				(width 0.1)
				(type default)
			)
			(layer "F.Fab")
		)
		(fp_line
			(start 0.120396 0.3048)
			(end 0.120396 0.2794)
			(stroke
				(width 0.1)
				(type default)
			)
			(layer "F.Fab")
		)
		(fp_line
			(start 0.67945 0.3048)
			(end 0.120396 0.3048)
			(stroke
				(width 0.1)
				(type default)
			)
			(layer "F.Fab")
		)
		(fp_line
			(start -0.12065 0.2794)
			(end -0.12065 0.3048)
			(stroke
				(width 0.1)
				(type default)
			)
			(layer "F.Fab")
		)
		(fp_line
			(start 0.120396 0.2794)
			(end -0.12065 0.2794)
			(stroke
				(width 0.1)
				(type default)
			)
			(layer "F.Fab")
		)
		(fp_line
			(start -0.12065 -0.2794)
			(end 0.12065 -0.2794)
			(stroke
				(width 0.1)
				(type default)
			)
			(layer "F.Fab")
		)
		(fp_line
			(start 0.12065 -0.2794)
			(end 0.12065 -0.3048)
			(stroke
				(width 0.1)
				(type default)
			)
			(layer "F.Fab")
		)
		(fp_line
			(start 0.12065 -0.3048)
			(end 0.67945 -0.3048)
			(stroke
				(width 0.1)
				(type default)
			)
			(layer "F.Fab")
		)
		(fp_line
			(start 0.67945 -0.3048)
			(end 0.67945 0.3048)
			(stroke
				(width 0.1)
				(type default)
			)
			(layer "F.Fab")
		)
		(fp_line
			(start -0.67945 -0.305054)
			(end -0.12065 -0.305054)
			(stroke
				(width 0.1)
				(type default)
			)
			(layer "F.Fab")
		)
		(fp_line
			(start -0.12065 -0.305054)
			(end -0.12065 -0.2794)
			(stroke
				(width 0.1)
				(type default)
			)
			(layer "F.Fab")
		)
		(pad "1" smd circle
			(at -0.40005 0 270)
			(size 0 0)
			(layers "F.Cu" "F.Mask" "F.Paste")
			(net "P3V3_AUX")
		)
		(pad "2" smd circle
			(at 0.40005 0 270)
			(size 0 0)
			(layers "F.Cu" "F.Mask" "F.Paste")
			(net "GND")
		)
	)
)
